(kicad_pcb
	(version 20260206)
	(generator "pcbnew")
	(generator_version "10.0")
	(general
		(thickness 1.6)
		(legacy_teardrops no)
	)
	(paper "A4")
	(title_block
		(title "03242023_DA0F0TMBIJ0_F0T_Motherboard_J_brd_V01_OCP.brd")
		(comment 1 "Grand Teton / footprint 1682 of 6105 (U1), pads 1602-1707 of 4677")
	)
	(layers
		(0 "F.Cu" signal "TOP")
		(4 "In1.Cu" signal "GND")
		(6 "In2.Cu" signal "IN1")
		(8 "In3.Cu" signal "GND1")
		(10 "In4.Cu" signal "IN2")
		(12 "In5.Cu" signal "GND2")
		(14 "In6.Cu" signal "IN3")
		(16 "In7.Cu" signal "GND3")
		(18 "In8.Cu" signal "VCC")
		(20 "In9.Cu" signal "VCC1")
		(22 "In10.Cu" signal "GND4")
		(24 "In11.Cu" signal "IN4")
		(26 "In12.Cu" signal "GND5")
		(28 "In13.Cu" signal "IN5")
		(30 "In14.Cu" signal "GND6")
		(32 "In15.Cu" signal "IN6")
		(34 "In16.Cu" signal "GND7")
		(2 "B.Cu" signal "BOTTOM")
		(9 "F.Adhes" user "F.Adhesive")
		(11 "B.Adhes" user "B.Adhesive")
		(13 "F.Paste" user "Package Geometry/Pastemask Top")
		(15 "B.Paste" user "Package Geometry/Pastemask Bottom")
		(5 "F.SilkS" user "Ref Des/Silkscreen Top")
		(7 "B.SilkS" user "Ref Des/Silkscreen Bottom")
		(1 "F.Mask" user "Board Geometry/Soldermask Top")
		(3 "B.Mask" user "Board Geometry/Soldermask Bottom")
		(17 "Dwgs.User" user "User.Drawings")
		(19 "Cmts.User" user "User.Comments")
		(21 "Eco1.User" user "User.Eco1")
		(23 "Eco2.User" user "User.Eco2")
		(25 "Edge.Cuts" user "Board Geometry/Outline")
		(27 "Margin" user)
		(31 "F.CrtYd" user "Package Geometry/Place Bound Top")
		(29 "B.CrtYd" user "Package Geometry/Place Bound Bottom")
		(35 "F.Fab" user "Ref Des/Assembly Top")
		(33 "B.Fab" user "Ref Des/Assembly Bottom")
	)
	(footprint ""
		(layer "F.Cu")
		(at 111.93018 -251.76988 90)
		(property "Reference" "U1"
			(at -74.913236 41.548812 0)
			(unlocked yes)
			(layer "F.SilkS")
			(effects
				(font
					(size 1.6002 1.1938)
					(thickness 0.1524)
				)
				(justify left)
			)
		)
		(property "Value" ""
			(at 0 0 90)
			(layer "F.Fab")
			(effects
				(font
					(size 1.27 1.27)
				)
			)
		)
		(duplicate_pad_numbers_are_jumpers no)
		(pad "BY24" smd circle
			(at -18.705576 0.649732 270)
			(size 0.4318 0.4318)
			(layers "F.Cu" "F.Mask" "F.Paste")
			(net "PD_EXT_CLK_SEL_CPU1")
		)
		(pad "BY26" smd circle
			(at -17.07769 0.649732 270)
			(size 0.4318 0.4318)
			(layers "F.Cu" "F.Mask" "F.Paste")
			(net "SMB_PEHPCPU1_GTL_SDA")
		)
		(pad "BY28" smd circle
			(at -15.450058 0.649732 270)
			(size 0.4318 0.4318)
			(layers "F.Cu" "F.Mask" "F.Paste")
			(net "TP_TRC_CPU1_PTI1_CLK")
		)
		(pad "BY30" smd circle
			(at -13.822426 0.649732 270)
			(size 0.4318 0.4318)
			(layers "F.Cu" "F.Mask" "F.Paste")
			(net "TP_TRC_CPU1_PTI<3>")
		)
		(pad "BY32" smd circle
			(at -12.19454 0.649732 270)
			(size 0.4318 0.4318)
			(layers "F.Cu" "F.Mask" "F.Paste")
			(net "PVCCIN_CPU1")
		)
		(pad "BY34" smd circle
			(at -10.566654 0.649732 270)
			(size 0.4318 0.4318)
			(layers "F.Cu" "F.Mask" "F.Paste")
			(net "PVCCIN_CPU1")
		)
		(pad "BY36" smd circle
			(at -8.939022 0.649732 270)
			(size 0.4318 0.4318)
			(layers "F.Cu" "F.Mask" "F.Paste")
			(net "PVCCIN_CPU1")
		)
		(pad "BY38" smd circle
			(at -7.311136 0.649732 270)
			(size 0.4318 0.4318)
			(layers "F.Cu" "F.Mask" "F.Paste")
			(net "PVCCIN_CPU1")
		)
		(pad "BY40" smd circle
			(at -5.68325 0.649732 270)
			(size 0.4318 0.4318)
			(layers "F.Cu" "F.Mask" "F.Paste")
			(net "PVCCIN_CPU1")
		)
		(pad "BY42" smd circle
			(at -4.055618 0.649732 270)
			(size 0.4318 0.4318)
			(layers "F.Cu" "F.Mask" "F.Paste")
			(net "PVCCIN_CPU1")
		)
		(pad "BY44" smd circle
			(at -2.427732 0.649732 270)
			(size 0.4318 0.4318)
			(layers "F.Cu" "F.Mask" "F.Paste")
			(net "PVCCIN_CPU1")
		)
		(pad "BY47" smd circle
			(at 1.613916 0.759714 270)
			(size 0.4318 0.4318)
			(layers "F.Cu" "F.Mask" "F.Paste")
			(net "PVCCIN_CPU1")
		)
		(pad "BY49" smd circle
			(at 3.241802 0.759714 270)
			(size 0.4318 0.4318)
			(layers "F.Cu" "F.Mask" "F.Paste")
			(net "PVCCIN_CPU1")
		)
		(pad "BY51" smd circle
			(at 4.869434 0.759714 270)
			(size 0.4318 0.4318)
			(layers "F.Cu" "F.Mask" "F.Paste")
			(net "PVCCIN_CPU1")
		)
		(pad "BY53" smd circle
			(at 6.49732 0.759714 270)
			(size 0.4318 0.4318)
			(layers "F.Cu" "F.Mask" "F.Paste")
			(net "PVCCIN_CPU1")
		)
		(pad "BY55" smd circle
			(at 8.124952 0.759714 270)
			(size 0.4318 0.4318)
			(layers "F.Cu" "F.Mask" "F.Paste")
			(net "PVCCIN_CPU1")
		)
		(pad "BY57" smd circle
			(at 9.752838 0.759714 270)
			(size 0.4318 0.4318)
			(layers "F.Cu" "F.Mask" "F.Paste")
			(net "PVCCIN_CPU1")
		)
		(pad "BY59" smd circle
			(at 11.380724 0.759714 270)
			(size 0.4318 0.4318)
			(layers "F.Cu" "F.Mask" "F.Paste")
			(net "PVCCIN_CPU1")
		)
		(pad "BY61" smd circle
			(at 13.008356 0.759714 270)
			(size 0.4318 0.4318)
			(layers "F.Cu" "F.Mask" "F.Paste")
			(net "PVCCIN_CPU1")
		)
		(pad "BY63" smd circle
			(at 14.635988 0.759714 270)
			(size 0.4318 0.4318)
			(layers "F.Cu" "F.Mask" "F.Paste")
			(net "PVCCIN_CPU1")
		)
		(pad "BY65" smd circle
			(at 16.263874 0.759714 270)
			(size 0.4318 0.4318)
			(layers "F.Cu" "F.Mask" "F.Paste")
			(net "PVCCIN_CPU1")
		)
		(pad "BY67" smd circle
			(at 17.89176 0.759714 270)
			(size 0.4318 0.4318)
			(layers "F.Cu" "F.Mask" "F.Paste")
			(net "PVCCIN_CPU1")
		)
		(pad "BY69" smd circle
			(at 19.519392 0.759714 270)
			(size 0.4318 0.4318)
			(layers "F.Cu" "F.Mask" "F.Paste")
			(net "PVCCIN_CPU1")
		)
		(pad "BY71" smd circle
			(at 21.147278 0.759714 270)
			(size 0.4318 0.4318)
			(layers "F.Cu" "F.Mask" "F.Paste")
			(net "PVCCIN_CPU1")
		)
		(pad "BY73" smd circle
			(at 22.77491 0.759714 270)
			(size 0.4318 0.4318)
			(layers "F.Cu" "F.Mask" "F.Paste")
			(net "PVCCIN_CPU1")
		)
		(pad "BY75" smd circle
			(at 24.402796 0.759714 270)
			(size 0.4318 0.4318)
			(layers "F.Cu" "F.Mask" "F.Paste")
			(net "PVCCIN_CPU1")
		)
		(pad "BY77" smd circle
			(at 26.030682 0.759714 270)
			(size 0.4318 0.4318)
			(layers "F.Cu" "F.Mask" "F.Paste")
			(net "PVCCIN_CPU1")
		)
		(pad "BY79" smd circle
			(at 27.658314 0.759714 270)
			(size 0.4318 0.4318)
			(layers "F.Cu" "F.Mask" "F.Paste")
			(net "PVCCIN_CPU1")
		)
		(pad "BY81" smd circle
			(at 29.2862 0.759714 270)
			(size 0.4318 0.4318)
			(layers "F.Cu" "F.Mask" "F.Paste")
			(net "PVCCIN_CPU1")
		)
		(pad "BY83" smd circle
			(at 30.914086 0.759714 270)
			(size 0.4318 0.4318)
			(layers "F.Cu" "F.Mask" "F.Paste")
			(net "PVCCIN_CPU1")
		)
		(pad "BY85" smd circle
			(at 32.541718 0.759714 270)
			(size 0.4318 0.4318)
			(layers "F.Cu" "F.Mask" "F.Paste")
			(net "PVCCIN_CPU1")
		)
		(pad "BY87" smd circle
			(at 34.169604 0.759714 270)
			(size 0.4318 0.4318)
			(layers "F.Cu" "F.Mask" "F.Paste")
			(net "PVCCIN_CPU1")
		)
		(pad "BY89" smd circle
			(at 35.797236 0.759714 270)
			(size 0.4318 0.4318)
			(layers "F.Cu" "F.Mask" "F.Paste")
			(net "PVCCIN_CPU1")
		)
		(pad "C5" smd oval
			(at -34.169604 -26.134314 135)
			(size 0.381 0.4826)
			(drill
				(offset 0 -0.0508)
			)
			(layers "F.Cu" "F.Mask" "F.Paste")
			(net "GND")
		)
		(pad "C7" smd oval
			(at -32.541718 -26.134314 135)
			(size 0.381 0.4826)
			(drill
				(offset 0 -0.0508)
			)
			(layers "F.Cu" "F.Mask" "F.Paste")
			(net "M_A_CPU1_SB_DQ<29>")
		)
		(pad "C9" smd oval
			(at -30.914086 -26.134314 90)
			(size 0.381 0.4826)
			(drill
				(offset 0 -0.0508)
			)
			(layers "F.Cu" "F.Mask" "F.Paste")
			(net "M_A_CPU1_SB_DQS_DP<3>")
		)
		(pad "C11" smd circle
			(at -29.2862 -26.134314 270)
			(size 0.4318 0.4318)
			(layers "F.Cu" "F.Mask" "F.Paste")
			(net "M_A_CPU1_SB_DQ<24>")
		)
		(pad "C13" smd circle
			(at -27.658314 -26.134314 270)
			(size 0.4318 0.4318)
			(layers "F.Cu" "F.Mask" "F.Paste")
			(net "M_B_CPU1_SB_DQ<28>")
		)
		(pad "C15" smd circle
			(at -26.030682 -26.134314 270)
			(size 0.4318 0.4318)
			(layers "F.Cu" "F.Mask" "F.Paste")
			(net "M_B_CPU1_SB_DQS_DP<3>")
		)
		(pad "C17" smd circle
			(at -24.402796 -26.134314 270)
			(size 0.4318 0.4318)
			(layers "F.Cu" "F.Mask" "F.Paste")
			(net "M_B_CPU1_SB_DQ<24>")
		)
		(pad "C19" smd circle
			(at -22.77491 -26.134314 270)
			(size 0.4318 0.4318)
			(layers "F.Cu" "F.Mask" "F.Paste")
			(net "M_A_CPU1_SB_DQ<21>")
		)
		(pad "C21" smd circle
			(at -21.147278 -26.134314 270)
			(size 0.4318 0.4318)
			(layers "F.Cu" "F.Mask" "F.Paste")
			(net "M_A_CPU1_SB_DQS_DP<2>")
		)
		(pad "C23" smd circle
			(at -19.519392 -26.134314 270)
			(size 0.4318 0.4318)
			(layers "F.Cu" "F.Mask" "F.Paste")
			(net "M_A_CPU1_SB_DQ<16>")
		)
		(pad "C25" smd circle
			(at -17.89176 -26.134314 270)
			(size 0.4318 0.4318)
			(layers "F.Cu" "F.Mask" "F.Paste")
			(net "M_A_CPU1_SB_DQ<13>")
		)
		(pad "C27" smd circle
			(at -16.263874 -26.134314 270)
			(size 0.4318 0.4318)
			(layers "F.Cu" "F.Mask" "F.Paste")
			(net "M_A_CPU1_SB_DQS_DP<1>")
		)
		(pad "C29" smd circle
			(at -14.635988 -26.134314 270)
			(size 0.4318 0.4318)
			(layers "F.Cu" "F.Mask" "F.Paste")
			(net "M_A_CPU1_SB_DQ<8>")
		)
		(pad "C31" smd circle
			(at -13.008356 -26.134314 270)
			(size 0.4318 0.4318)
			(layers "F.Cu" "F.Mask" "F.Paste")
			(net "M_A_CPU1_SB_CB<1>")
		)
		(pad "C33" smd circle
			(at -11.380724 -26.134314 270)
			(size 0.4318 0.4318)
			(layers "F.Cu" "F.Mask" "F.Paste")
			(net "M_A_CPU1_SB_DQS_DP<9>")
		)
		(pad "C35" smd circle
			(at -9.752838 -26.134314 270)
			(size 0.4318 0.4318)
			(layers "F.Cu" "F.Mask" "F.Paste")
			(net "M_A_CPU1_SB_CB<4>")
		)
		(pad "C37" smd circle
			(at -8.124952 -26.134314 270)
			(size 0.4318 0.4318)
			(layers "F.Cu" "F.Mask" "F.Paste")
			(net "M_A_CPU1_SB_CS_N<1>")
		)
		(pad "C39" smd circle
			(at -6.49732 -26.134314 270)
			(size 0.4318 0.4318)
			(layers "F.Cu" "F.Mask" "F.Paste")
			(net "GND")
		)
		(pad "C41" smd circle
			(at -4.869434 -26.134314 270)
			(size 0.4318 0.4318)
			(layers "F.Cu" "F.Mask" "F.Paste")
			(net "M_A_CPU1_SB_CA<2>")
		)
		(pad "C43" smd circle
			(at -3.241802 -26.134314 270)
			(size 0.4318 0.4318)
			(layers "F.Cu" "F.Mask" "F.Paste")
			(net "M_A_CPU1_CLK_DP<0>")
		)
		(pad "C45" smd oval
			(at -1.613916 -26.134314 45)
			(size 0.381 0.4826)
			(drill
				(offset 0 -0.0508)
			)
			(layers "F.Cu" "F.Mask" "F.Paste")
			(net "GND")
		)
		(pad "C48" smd oval
			(at 2.427732 -26.024586 135)
			(size 0.381 0.4826)
			(drill
				(offset 0 -0.0508)
			)
			(layers "F.Cu" "F.Mask" "F.Paste")
			(net "M_A_CPU1_SA_CA<6>")
		)
		(pad "C50" smd circle
			(at 4.055618 -26.024586 270)
			(size 0.4318 0.4318)
			(layers "F.Cu" "F.Mask" "F.Paste")
			(net "M_A_CPU1_SA_CA<4>")
		)
		(pad "C52" smd circle
			(at 5.68325 -26.024586 270)
			(size 0.4318 0.4318)
			(layers "F.Cu" "F.Mask" "F.Paste")
			(net "GND")
		)
		(pad "C54" smd circle
			(at 7.311136 -26.024586 270)
			(size 0.4318 0.4318)
			(layers "F.Cu" "F.Mask" "F.Paste")
			(net "M_A_CPU1_SA_CS_N<0>")
		)
		(pad "C56" smd circle
			(at 8.939022 -26.024586 270)
			(size 0.4318 0.4318)
			(layers "F.Cu" "F.Mask" "F.Paste")
			(net "M_A_CPU1_SA_CB<5>")
		)
		(pad "C58" smd circle
			(at 10.566654 -26.024586 270)
			(size 0.4318 0.4318)
			(layers "F.Cu" "F.Mask" "F.Paste")
			(net "M_A_CPU1_SA_DQS_DP<4>")
		)
		(pad "C60" smd circle
			(at 12.19454 -26.024586 270)
			(size 0.4318 0.4318)
			(layers "F.Cu" "F.Mask" "F.Paste")
			(net "M_A_CPU1_SA_CB<0>")
		)
		(pad "C62" smd circle
			(at 13.822426 -26.024586 270)
			(size 0.4318 0.4318)
			(layers "F.Cu" "F.Mask" "F.Paste")
			(net "M_A_CPU1_SA_DQ<29>")
		)
		(pad "C64" smd circle
			(at 15.450058 -26.024586 270)
			(size 0.4318 0.4318)
			(layers "F.Cu" "F.Mask" "F.Paste")
			(net "M_A_CPU1_SA_DQS_DP<3>")
		)
		(pad "C66" smd circle
			(at 17.07769 -26.024586 270)
			(size 0.4318 0.4318)
			(layers "F.Cu" "F.Mask" "F.Paste")
			(net "M_A_CPU1_SA_DQ<24>")
		)
		(pad "C68" smd circle
			(at 18.705576 -26.024586 270)
			(size 0.4318 0.4318)
			(layers "F.Cu" "F.Mask" "F.Paste")
			(net "M_A_CPU1_SA_DQ<21>")
		)
		(pad "C70" smd circle
			(at 20.333462 -26.024586 270)
			(size 0.4318 0.4318)
			(layers "F.Cu" "F.Mask" "F.Paste")
			(net "M_A_CPU1_SA_DQS_DP<2>")
		)
		(pad "C72" smd circle
			(at 21.961094 -26.024586 270)
			(size 0.4318 0.4318)
			(layers "F.Cu" "F.Mask" "F.Paste")
			(net "GND")
		)
		(pad "C74" smd circle
			(at 23.58898 -26.024586 270)
			(size 0.4318 0.4318)
			(layers "F.Cu" "F.Mask" "F.Paste")
			(net "GND")
		)
		(pad "C76" smd circle
			(at 25.216612 -26.024586 270)
			(size 0.4318 0.4318)
			(layers "F.Cu" "F.Mask" "F.Paste")
			(net "M_A_CPU1_SA_DQ<4>")
		)
		(pad "C78" smd circle
			(at 26.844498 -26.024586 270)
			(size 0.4318 0.4318)
			(layers "F.Cu" "F.Mask" "F.Paste")
			(net "GND")
		)
		(pad "C80" smd circle
			(at 28.472384 -26.024586 270)
			(size 0.4318 0.4318)
			(layers "F.Cu" "F.Mask" "F.Paste")
			(net "GND")
		)
		(pad "C82" smd circle
			(at 30.100016 -26.024586 270)
			(size 0.4318 0.4318)
			(layers "F.Cu" "F.Mask" "F.Paste")
			(net "GND")
		)
		(pad "C84" smd oval
			(at 31.727902 -26.024586 45)
			(size 0.381 0.4826)
			(drill
				(offset 0 -0.0508)
			)
			(layers "F.Cu" "F.Mask" "F.Paste")
			(net "PVCCFA_EHV_FIVRA_CPU1")
		)
		(pad "C86" smd oval
			(at 33.355534 -26.024586 45)
			(size 0.381 0.4826)
			(drill
				(offset 0 -0.0508)
			)
			(layers "F.Cu" "F.Mask" "F.Paste")
			(net "GND")
		)
		(pad "C88" smd oval
			(at 34.98342 -26.024586 45)
			(size 0.381 0.4826)
			(drill
				(offset 0 -0.0508)
			)
			(layers "F.Cu" "F.Mask" "F.Paste")
			(net "PVCCFA_EHV_FIVRA_CPU1")
		)
		(pad "CA3" smd circle
			(at -35.797236 1.119886 270)
			(size 0.4318 0.4318)
			(layers "F.Cu" "F.Mask" "F.Paste")
			(net "GND")
		)
		(pad "CA5" smd circle
			(at -34.169604 1.119886 270)
			(size 0.4318 0.4318)
			(layers "F.Cu" "F.Mask" "F.Paste")
			(net "UPI_CPU1_CPU0_P1P0_DN<22>")
		)
		(pad "CA7" smd circle
			(at -32.541718 1.119886 270)
			(size 0.4318 0.4318)
			(layers "F.Cu" "F.Mask" "F.Paste")
			(net "PVCCD_HV_CPU1")
		)
		(pad "CA9" smd circle
			(at -30.914086 1.119886 270)
			(size 0.4318 0.4318)
			(layers "F.Cu" "F.Mask" "F.Paste")
			(net "P5E_CPU1_PE1_RX_DP<6>")
		)
		(pad "CA11" smd circle
			(at -29.2862 1.119886 270)
			(size 0.4318 0.4318)
			(layers "F.Cu" "F.Mask" "F.Paste")
			(net "VSENSE_PVCCINFAON_CPU1_DP")
		)
		(pad "CA13" smd circle
			(at -27.658314 1.119886 270)
			(size 0.4318 0.4318)
			(layers "F.Cu" "F.Mask" "F.Paste")
			(net "P5E_CPU1_PE1_TX_DN<7>")
		)
		(pad "CA15" smd circle
			(at -26.030682 1.119886 270)
			(size 0.4318 0.4318)
			(layers "F.Cu" "F.Mask" "F.Paste")
			(net "PVCCINFAON_CPU1")
		)
		(pad "CA17" smd circle
			(at -24.402796 1.119886 270)
			(size 0.4318 0.4318)
			(layers "F.Cu" "F.Mask" "F.Paste")
			(net "TP_DMI_CPU1_PCH_TX_DN<1>")
		)
		(pad "CA19" smd circle
			(at -22.77491 1.119886 270)
			(size 0.4318 0.4318)
			(layers "F.Cu" "F.Mask" "F.Paste")
			(net "TP_DMI_CPU1_PCH_TX_DP<0>")
		)
		(pad "CA21" smd circle
			(at -21.147278 1.119886 270)
			(size 0.4318 0.4318)
			(layers "F.Cu" "F.Mask" "F.Paste")
			(net "NC_CPU1_DMI_APROBE<0>")
		)
		(pad "CA23" smd circle
			(at -19.519392 1.119886 270)
			(size 0.4318 0.4318)
			(layers "F.Cu" "F.Mask" "F.Paste")
			(net "NC_CPU1_UPI1_APROBE<1>")
		)
		(pad "CA25" smd circle
			(at -17.89176 1.119886 270)
			(size 0.4318 0.4318)
			(layers "F.Cu" "F.Mask" "F.Paste")
			(net "SMB_PEHPCPU1_GTL_SCL")
		)
		(pad "CA27" smd circle
			(at -16.263874 1.119886 270)
			(size 0.4318 0.4318)
			(layers "F.Cu" "F.Mask" "F.Paste")
			(net "TP_TRC_CPU1_PTI<6>")
		)
		(pad "CA29" smd circle
			(at -14.635988 1.119886 270)
			(size 0.4318 0.4318)
			(layers "F.Cu" "F.Mask" "F.Paste")
			(net "TP_TRC_CPU1_PTI<4>")
		)
		(pad "CA31" smd circle
			(at -13.008356 1.119886 270)
			(size 0.4318 0.4318)
			(layers "F.Cu" "F.Mask" "F.Paste")
			(net "GND")
		)
		(pad "CA33" smd circle
			(at -11.380724 1.119886 270)
			(size 0.4318 0.4318)
			(layers "F.Cu" "F.Mask" "F.Paste")
			(net "PVCCIN_CPU1")
		)
		(pad "CA35" smd circle
			(at -9.752838 1.119886 270)
			(size 0.4318 0.4318)
			(layers "F.Cu" "F.Mask" "F.Paste")
			(net "PVCCIN_CPU1")
		)
		(pad "CA37" smd circle
			(at -8.124952 1.119886 270)
			(size 0.4318 0.4318)
			(layers "F.Cu" "F.Mask" "F.Paste")
			(net "PVCCIN_CPU1")
		)
		(pad "CA39" smd circle
			(at -6.49732 1.119886 270)
			(size 0.4318 0.4318)
			(layers "F.Cu" "F.Mask" "F.Paste")
			(net "PVCCIN_CPU1")
		)
		(pad "CA41" smd circle
			(at -4.869434 1.119886 270)
			(size 0.4318 0.4318)
			(layers "F.Cu" "F.Mask" "F.Paste")
			(net "PVCCIN_CPU1")
		)
		(pad "CA43" smd circle
			(at -3.241802 1.119886 270)
			(size 0.4318 0.4318)
			(layers "F.Cu" "F.Mask" "F.Paste")
			(net "PVCCIN_CPU1")
		)
		(pad "CA45" smd circle
			(at -1.613916 1.119886 270)
			(size 0.4318 0.4318)
			(layers "F.Cu" "F.Mask" "F.Paste")
			(net "PVCCIN_CPU1")
		)
		(pad "CA48" smd circle
			(at 2.427732 1.229614 270)
			(size 0.4318 0.4318)
			(layers "F.Cu" "F.Mask" "F.Paste")
			(net "PVCCIN_CPU1")
		)
		(pad "CA50" smd circle
			(at 4.055618 1.229614 270)
			(size 0.4318 0.4318)
			(layers "F.Cu" "F.Mask" "F.Paste")
			(net "PVCCIN_CPU1")
		)
		(pad "CA52" smd circle
			(at 5.68325 1.229614 270)
			(size 0.4318 0.4318)
			(layers "F.Cu" "F.Mask" "F.Paste")
			(net "PVCCIN_CPU1")
		)
		(pad "CA54" smd circle
			(at 7.311136 1.229614 270)
			(size 0.4318 0.4318)
			(layers "F.Cu" "F.Mask" "F.Paste")
			(net "PVCCIN_CPU1")
		)
		(pad "CA56" smd circle
			(at 8.939022 1.229614 270)
			(size 0.4318 0.4318)
			(layers "F.Cu" "F.Mask" "F.Paste")
			(net "PVCCIN_CPU1")
		)
		(pad "CA58" smd circle
			(at 10.566654 1.229614 270)
			(size 0.4318 0.4318)
			(layers "F.Cu" "F.Mask" "F.Paste")
			(net "PVCCIN_CPU1")
		)
		(pad "CA60" smd circle
			(at 12.19454 1.229614 270)
			(size 0.4318 0.4318)
			(layers "F.Cu" "F.Mask" "F.Paste")
			(net "PVCCIN_CPU1")
		)
		(pad "CA62" smd circle
			(at 13.822426 1.229614 270)
			(size 0.4318 0.4318)
			(layers "F.Cu" "F.Mask" "F.Paste")
			(net "PVCCIN_CPU1")
		)
		(pad "CA64" smd circle
			(at 15.450058 1.229614 270)
			(size 0.4318 0.4318)
			(layers "F.Cu" "F.Mask" "F.Paste")
			(net "PVCCIN_CPU1")
		)
	)
)
